(kicad_pcb
	(version 20260206)
	(generator "pcbnew")
	(generator_version "10.0")
	(general
		(thickness 1.6)
		(legacy_teardrops no)
	)
	(paper "A4")
	(title_block
		(title "Bryce Canyon_IOM_M2_16342-2_OCP.brd")
		(comment 1 "Bryce Canyon / footprints 610-615 of 1146")
	)
	(layers
		(0 "F.Cu" signal "TOP")
		(4 "In1.Cu" signal "L2GND")
		(6 "In2.Cu" signal "L3")
		(8 "In3.Cu" signal "L4VCC")
		(10 "In4.Cu" signal "L5VCC")
		(12 "In5.Cu" signal "L6")
		(14 "In6.Cu" signal "L7GND")
		(2 "B.Cu" signal "BOTTOM")
		(9 "F.Adhes" user "F.Adhesive")
		(11 "B.Adhes" user "B.Adhesive")
		(13 "F.Paste" user "Package Geometry/Pastemask Top")
		(15 "B.Paste" user "Package Geometry/Pastemask Bottom")
		(5 "F.SilkS" user "Ref Des/Silkscreen Top")
		(7 "B.SilkS" user "Ref Des/Silkscreen Bottom")
		(1 "F.Mask" user "Board Geometry/Soldermask Top")
		(3 "B.Mask" user "Board Geometry/Soldermask Bottom")
		(17 "Dwgs.User" user "User.Drawings")
		(19 "Cmts.User" user "User.Comments")
		(21 "Eco1.User" user "User.Eco1")
		(23 "Eco2.User" user "User.Eco2")
		(25 "Edge.Cuts" user "Board Geometry/Outline")
		(27 "Margin" user)
		(31 "F.CrtYd" user "Package Geometry/Place Bound Top")
		(29 "B.CrtYd" user "Package Geometry/Place Bound Bottom")
		(35 "F.Fab" user "Ref Des/Assembly Top")
		(33 "B.Fab" user "Ref Des/Assembly Bottom")
	)
	(footprint ""
		(layer "F.Cu")
		(at 112.87379 -7.736078 -90)
		(property "Reference" "R459"
			(at 0 0 270)
			(layer "F.SilkS")
			(hide yes)
			(effects
				(font
					(size 1.27 1.27)
				)
			)
		)
		(property "Value" "0R2J-2-GP"
			(at 0.064008 -3.993896 270)
			(unlocked yes)
			(layer "F.Fab")
			(hide yes)
			(effects
				(font
					(size 1.016 1.016)
					(thickness 0.1524)
				)
			)
		)
		(property "Device Type" "R402H16"
			(at 0.064008 -5.517896 270)
			(unlocked yes)
			(layer "F.Fab")
			(hide yes)
			(effects
				(font
					(size 1.016 1.016)
					(thickness 0.1524)
				)
			)
		)
		(duplicate_pad_numbers_are_jumpers no)
		(fp_line
			(start -0.508 -0.9398)
			(end -0.508 0.9398)
			(stroke
				(width 0.1524)
				(type default)
			)
			(layer "F.SilkS")
		)
		(fp_line
			(start 0.508 -0.9398)
			(end -0.508 -0.9398)
			(stroke
				(width 0.1524)
				(type default)
			)
			(layer "F.SilkS")
		)
		(fp_rect
			(start -0.508 0.9398)
			(end 0.508 -0.9398)
			(stroke
				(width 0)
				(type default)
			)
			(fill no)
			(layer "F.CrtYd")
		)
		(fp_rect
			(start -0.508 0.9398)
			(end 0.508 -0.9398)
			(stroke
				(width 0)
				(type default)
			)
			(fill no)
			(layer "F.Fab")
		)
		(pad "1" smd custom
			(at 0 -0.4445 270)
			(size 0.1397 0.1397)
			(layers "F.Cu" "F.Mask" "F.Paste")
			(net "MB0_CM_ADR1_R")
			(options
				(clearance outline)
				(anchor circle)
			)
			(primitives
				(gr_poly
					(pts
						(arc
							(start -0.1778 -0.2794)
							(mid -0.249642 -0.249642)
							(end -0.2794 -0.1778)
						)
						(arc
							(start -0.2794 0.1778)
							(mid -0.249642 0.249642)
							(end -0.1778 0.2794)
						)
						(arc
							(start 0.1778 0.2794)
							(mid 0.249642 0.249642)
							(end 0.2794 0.1778)
						)
						(arc
							(start 0.2794 -0.1778)
							(mid 0.249642 -0.249642)
							(end 0.1778 -0.2794)
						)
					)
					(width 0)
					(fill yes)
				)
			)
		)
		(pad "2" smd custom
			(at 0 0.4445 270)
			(size 0.1397 0.1397)
			(layers "F.Cu" "F.Mask" "F.Paste")
			(net "AGND_CURRENT_MON")
			(options
				(clearance outline)
				(anchor circle)
			)
			(primitives
				(gr_poly
					(pts
						(arc
							(start -0.1778 -0.2794)
							(mid -0.249642 -0.249642)
							(end -0.2794 -0.1778)
						)
						(arc
							(start -0.2794 0.1778)
							(mid -0.249642 0.249642)
							(end -0.1778 0.2794)
						)
						(arc
							(start 0.1778 0.2794)
							(mid 0.249642 0.249642)
							(end 0.2794 0.1778)
						)
						(arc
							(start 0.2794 -0.1778)
							(mid 0.249642 -0.249642)
							(end 0.1778 -0.2794)
						)
					)
					(width 0)
					(fill yes)
				)
			)
		)
	)
	(footprint ""
		(layer "F.Cu")
		(at 29.456634 -151.499316 -90)
		(property "Reference" "R768"
			(at 0 0 270)
			(layer "F.SilkS")
			(hide yes)
			(effects
				(font
					(size 1.27 1.27)
				)
			)
		)
		(property "Value" "0R2J-2-GP"
			(at 0.064008 -3.993896 270)
			(unlocked yes)
			(layer "F.Fab")
			(hide yes)
			(effects
				(font
					(size 1.016 1.016)
					(thickness 0.1524)
				)
			)
		)
		(property "Device Type" "R402H16"
			(at 0.064008 -5.517896 270)
			(unlocked yes)
			(layer "F.Fab")
			(hide yes)
			(effects
				(font
					(size 1.016 1.016)
					(thickness 0.1524)
				)
			)
		)
		(duplicate_pad_numbers_are_jumpers no)
		(fp_line
			(start -0.508 -0.9398)
			(end -0.508 0.9398)
			(stroke
				(width 0.1524)
				(type default)
			)
			(layer "F.SilkS")
		)
		(fp_line
			(start 0.508 -0.9398)
			(end -0.508 -0.9398)
			(stroke
				(width 0.1524)
				(type default)
			)
			(layer "F.SilkS")
		)
		(fp_rect
			(start -0.508 0.9398)
			(end 0.508 -0.9398)
			(stroke
				(width 0)
				(type default)
			)
			(fill no)
			(layer "F.CrtYd")
		)
		(fp_rect
			(start -0.508 0.9398)
			(end 0.508 -0.9398)
			(stroke
				(width 0)
				(type default)
			)
			(fill no)
			(layer "F.Fab")
		)
		(pad "1" smd custom
			(at 0 -0.4445 270)
			(size 0.1397 0.1397)
			(layers "F.Cu" "F.Mask" "F.Paste")
			(net "DEBUG_GPIO_BMC_R_1")
			(options
				(clearance outline)
				(anchor circle)
			)
			(primitives
				(gr_poly
					(pts
						(arc
							(start -0.1778 -0.2794)
							(mid -0.249642 -0.249642)
							(end -0.2794 -0.1778)
						)
						(arc
							(start -0.2794 0.1778)
							(mid -0.249642 0.249642)
							(end -0.1778 0.2794)
						)
						(arc
							(start 0.1778 0.2794)
							(mid 0.249642 0.249642)
							(end 0.2794 0.1778)
						)
						(arc
							(start 0.2794 -0.1778)
							(mid 0.249642 -0.249642)
							(end 0.1778 -0.2794)
						)
					)
					(width 0)
					(fill yes)
				)
			)
		)
		(pad "2" smd custom
			(at 0 0.4445 270)
			(size 0.1397 0.1397)
			(layers "F.Cu" "F.Mask" "F.Paste")
			(net "DEBUG_GPIO_BMC_1")
			(options
				(clearance outline)
				(anchor circle)
			)
			(primitives
				(gr_poly
					(pts
						(arc
							(start -0.1778 -0.2794)
							(mid -0.249642 -0.249642)
							(end -0.2794 -0.1778)
						)
						(arc
							(start -0.2794 0.1778)
							(mid -0.249642 0.249642)
							(end -0.1778 0.2794)
						)
						(arc
							(start 0.1778 0.2794)
							(mid 0.249642 0.249642)
							(end 0.2794 0.1778)
						)
						(arc
							(start 0.2794 -0.1778)
							(mid 0.249642 -0.249642)
							(end 0.1778 -0.2794)
						)
					)
					(width 0)
					(fill yes)
				)
			)
		)
	)
	(footprint ""
		(layer "F.Cu")
		(at 30.3276 -162.7378 180)
		(property "Reference" "C105"
			(at 0 0 180)
			(layer "F.SilkS")
			(hide yes)
			(effects
				(font
					(size 1.27 1.27)
				)
			)
		)
		(property "Value" "SC100P50V2JN-3GP"
			(at 1.1811 -2.7051 180)
			(unlocked yes)
			(layer "F.Fab")
			(hide yes)
			(effects
				(font
					(size 1.016 1.016)
					(thickness 0.1524)
				)
			)
		)
		(property "Device Type" "C402H22"
			(at 1.1811 -4.2291 180)
			(unlocked yes)
			(layer "F.Fab")
			(hide yes)
			(effects
				(font
					(size 1.016 1.016)
					(thickness 0.1524)
				)
			)
		)
		(duplicate_pad_numbers_are_jumpers no)
		(fp_rect
			(start -0.4318 0.9525)
			(end 0.4318 -0.9525)
			(stroke
				(width 0)
				(type default)
			)
			(fill no)
			(layer "F.CrtYd")
		)
		(fp_rect
			(start -0.4318 0.9525)
			(end 0.4318 -0.9525)
			(stroke
				(width 0)
				(type default)
			)
			(fill no)
			(layer "F.Fab")
		)
		(pad "1" smd custom
			(at 0 -0.4445 180)
			(size 0.1524 0.1524)
			(layers "F.Cu" "F.Mask" "F.Paste")
			(net "V1PLLAV11")
			(options
				(clearance outline)
				(anchor circle)
			)
			(primitives
				(gr_poly
					(pts
						(arc
							(start 0.3048 -0.2032)
							(mid 0.275042 -0.275042)
							(end 0.2032 -0.3048)
						)
						(arc
							(start -0.2032 -0.3048)
							(mid -0.275042 -0.275042)
							(end -0.3048 -0.2032)
						)
						(arc
							(start -0.3048 0.2032)
							(mid -0.275042 0.275042)
							(end -0.2032 0.3048)
						)
						(arc
							(start 0.2032 0.3048)
							(mid 0.275042 0.275042)
							(end 0.3048 0.2032)
						)
					)
					(width 0)
					(fill yes)
				)
			)
		)
		(pad "2" smd custom
			(at 0 0.4445 180)
			(size 0.1524 0.1524)
			(layers "F.Cu" "F.Mask" "F.Paste")
			(net "GND")
			(options
				(clearance outline)
				(anchor circle)
			)
			(primitives
				(gr_poly
					(pts
						(arc
							(start 0.3048 -0.2032)
							(mid 0.275042 -0.275042)
							(end 0.2032 -0.3048)
						)
						(arc
							(start -0.2032 -0.3048)
							(mid -0.275042 -0.275042)
							(end -0.3048 -0.2032)
						)
						(arc
							(start -0.3048 0.2032)
							(mid -0.275042 0.275042)
							(end -0.2032 0.3048)
						)
						(arc
							(start 0.2032 0.3048)
							(mid 0.275042 0.275042)
							(end 0.3048 0.2032)
						)
					)
					(width 0)
					(fill yes)
				)
			)
		)
	)
	(footprint ""
		(layer "F.Cu")
		(at 207.8736 -109.22 -90)
		(property "Reference" "R554"
			(at 0 0 270)
			(layer "F.SilkS")
			(hide yes)
			(effects
				(font
					(size 1.27 1.27)
				)
			)
		)
		(property "Value" "4K7R2F-GP"
			(at 0.064008 -3.993896 270)
			(unlocked yes)
			(layer "F.Fab")
			(hide yes)
			(effects
				(font
					(size 1.016 1.016)
					(thickness 0.1524)
				)
			)
		)
		(property "Device Type" "R402H16"
			(at 0.064008 -5.517896 270)
			(unlocked yes)
			(layer "F.Fab")
			(hide yes)
			(effects
				(font
					(size 1.016 1.016)
					(thickness 0.1524)
				)
			)
		)
		(duplicate_pad_numbers_are_jumpers no)
		(fp_line
			(start -0.508 -0.9398)
			(end -0.508 0.9398)
			(stroke
				(width 0.1524)
				(type default)
			)
			(layer "F.SilkS")
		)
		(fp_line
			(start 0.508 -0.9398)
			(end -0.508 -0.9398)
			(stroke
				(width 0.1524)
				(type default)
			)
			(layer "F.SilkS")
		)
		(fp_rect
			(start -0.508 0.9398)
			(end 0.508 -0.9398)
			(stroke
				(width 0)
				(type default)
			)
			(fill no)
			(layer "F.CrtYd")
		)
		(fp_rect
			(start -0.508 0.9398)
			(end 0.508 -0.9398)
			(stroke
				(width 0)
				(type default)
			)
			(fill no)
			(layer "F.Fab")
		)
		(pad "1" smd custom
			(at 0 -0.4445 270)
			(size 0.1397 0.1397)
			(layers "F.Cu" "F.Mask" "F.Paste")
			(net "P3V3_STBY")
			(options
				(clearance outline)
				(anchor circle)
			)
			(primitives
				(gr_poly
					(pts
						(arc
							(start -0.1778 -0.2794)
							(mid -0.249642 -0.249642)
							(end -0.2794 -0.1778)
						)
						(arc
							(start -0.2794 0.1778)
							(mid -0.249642 0.249642)
							(end -0.1778 0.2794)
						)
						(arc
							(start 0.1778 0.2794)
							(mid 0.249642 0.249642)
							(end 0.2794 0.1778)
						)
						(arc
							(start 0.2794 -0.1778)
							(mid 0.249642 -0.249642)
							(end 0.1778 -0.2794)
						)
					)
					(width 0)
					(fill yes)
				)
			)
		)
		(pad "2" smd custom
			(at 0 0.4445 270)
			(size 0.1397 0.1397)
			(layers "F.Cu" "F.Mask" "F.Paste")
			(net "TEMP_2_A2")
			(options
				(clearance outline)
				(anchor circle)
			)
			(primitives
				(gr_poly
					(pts
						(arc
							(start -0.1778 -0.2794)
							(mid -0.249642 -0.249642)
							(end -0.2794 -0.1778)
						)
						(arc
							(start -0.2794 0.1778)
							(mid -0.249642 0.249642)
							(end -0.1778 0.2794)
						)
						(arc
							(start 0.1778 0.2794)
							(mid 0.249642 0.249642)
							(end 0.2794 0.1778)
						)
						(arc
							(start 0.2794 -0.1778)
							(mid 0.249642 -0.249642)
							(end 0.1778 -0.2794)
						)
					)
					(width 0)
					(fill yes)
				)
			)
		)
	)
	(footprint ""
		(layer "F.Cu")
		(at 62.865 -178.816)
		(property "Reference" "R356"
			(at 0 0 0)
			(layer "F.SilkS")
			(hide yes)
			(effects
				(font
					(size 1.27 1.27)
				)
			)
		)
		(property "Value" "0R2J-2-GP"
			(at 0.064008 -3.993896 0)
			(unlocked yes)
			(layer "F.Fab")
			(hide yes)
			(effects
				(font
					(size 1.016 1.016)
					(thickness 0.1524)
				)
			)
		)
		(property "Device Type" "R402H16"
			(at 0.064008 -5.517896 0)
			(unlocked yes)
			(layer "F.Fab")
			(hide yes)
			(effects
				(font
					(size 1.016 1.016)
					(thickness 0.1524)
				)
			)
		)
		(duplicate_pad_numbers_are_jumpers no)
		(fp_line
			(start -0.508 -0.9398)
			(end -0.508 0.9398)
			(stroke
				(width 0.1524)
				(type default)
			)
			(layer "F.SilkS")
		)
		(fp_line
			(start 0.508 -0.9398)
			(end -0.508 -0.9398)
			(stroke
				(width 0.1524)
				(type default)
			)
			(layer "F.SilkS")
		)
		(fp_rect
			(start -0.508 0.9398)
			(end 0.508 -0.9398)
			(stroke
				(width 0)
				(type default)
			)
			(fill no)
			(layer "F.CrtYd")
		)
		(fp_rect
			(start -0.508 0.9398)
			(end 0.508 -0.9398)
			(stroke
				(width 0)
				(type default)
			)
			(fill no)
			(layer "F.Fab")
		)
		(pad "1" smd custom
			(at 0 -0.4445)
			(size 0.1397 0.1397)
			(layers "F.Cu" "F.Mask" "F.Paste")
			(net "IOM_STBY_PGOOD")
			(options
				(clearance outline)
				(anchor circle)
			)
			(primitives
				(gr_poly
					(pts
						(arc
							(start -0.1778 -0.2794)
							(mid -0.249642 -0.249642)
							(end -0.2794 -0.1778)
						)
						(arc
							(start -0.2794 0.1778)
							(mid -0.249642 0.249642)
							(end -0.1778 0.2794)
						)
						(arc
							(start 0.1778 0.2794)
							(mid 0.249642 0.249642)
							(end 0.2794 0.1778)
						)
						(arc
							(start 0.2794 -0.1778)
							(mid 0.249642 -0.249642)
							(end 0.1778 -0.2794)
						)
					)
					(width 0)
					(fill yes)
				)
			)
		)
		(pad "2" smd custom
			(at 0 0.4445)
			(size 0.1397 0.1397)
			(layers "F.Cu" "F.Mask" "F.Paste")
			(net "FM_BMC_RESET_N")
			(options
				(clearance outline)
				(anchor circle)
			)
			(primitives
				(gr_poly
					(pts
						(arc
							(start -0.1778 -0.2794)
							(mid -0.249642 -0.249642)
							(end -0.2794 -0.1778)
						)
						(arc
							(start -0.2794 0.1778)
							(mid -0.249642 0.249642)
							(end -0.1778 0.2794)
						)
						(arc
							(start 0.1778 0.2794)
							(mid 0.249642 0.249642)
							(end 0.2794 0.1778)
						)
						(arc
							(start 0.2794 -0.1778)
							(mid 0.249642 -0.249642)
							(end 0.1778 -0.2794)
						)
					)
					(width 0)
					(fill yes)
				)
			)
		)
	)
	(footprint ""
		(layer "F.Cu")
		(at 75.091036 -180.35778 -90)
		(property "Reference" "PU9"
			(at 0 0 270)
			(layer "F.SilkS")
			(hide yes)
			(effects
				(font
					(size 1.27 1.27)
				)
			)
		)
		(property "Value" "TPS74801RGW-GP"
			(at -4.7244 -6.223 270)
			(unlocked yes)
			(layer "F.Fab")
			(hide yes)
			(effects
				(font
					(size 1.016 1.016)
					(thickness 0.1524)
				)
			)
		)
		(property "Device Type" "QFN20-1G3D15H40"
			(at -4.7244 -7.747 270)
			(unlocked yes)
			(layer "F.Fab")
			(hide yes)
			(effects
				(font
					(size 1.016 1.016)
					(thickness 0.1524)
				)
			)
		)
		(duplicate_pad_numbers_are_jumpers no)
		(fp_line
			(start -3.5179 3.5179)
			(end -2.2479 3.5179)
			(stroke
				(width 0.1524)
				(type default)
			)
			(layer "F.SilkS")
		)
		(fp_line
			(start 2.2479 3.5179)
			(end 3.5179 3.5179)
			(stroke
				(width 0.1524)
				(type default)
			)
			(layer "F.SilkS")
		)
		(fp_line
			(start 3.5179 3.5179)
			(end 3.5179 2.2479)
			(stroke
				(width 0.1524)
				(type default)
			)
			(layer "F.SilkS")
		)
		(fp_line
			(start 1.299972 3.160522)
			(end 1.299972 3.668522)
			(stroke
				(width 0.1524)
				(type default)
			)
			(layer "F.SilkS")
		)
		(fp_line
			(start -3.5179 2.2479)
			(end -3.5179 3.5179)
			(stroke
				(width 0.1524)
				(type default)
			)
			(layer "F.SilkS")
		)
		(fp_line
			(start -3.160522 1.299972)
			(end -3.922522 1.299972)
			(stroke
				(width 0.1524)
				(type default)
			)
			(layer "F.SilkS")
		)
		(fp_line
			(start 3.160522 -1.299972)
			(end 3.922522 -1.299972)
			(stroke
				(width 0.1524)
				(type default)
			)
			(layer "F.SilkS")
		)
		(fp_line
			(start -1.299972 -3.160522)
			(end -1.299972 -3.668522)
			(stroke
				(width 0.1524)
				(type default)
			)
			(layer "F.SilkS")
		)
		(fp_line
			(start -3.5179 -3.5179)
			(end -3.5179 -2.2479)
			(stroke
				(width 0.1524)
				(type default)
			)
			(layer "F.SilkS")
		)
		(fp_line
			(start -2.2479 -3.5179)
			(end -3.5179 -3.5179)
			(stroke
				(width 0.1524)
				(type default)
			)
			(layer "F.SilkS")
		)
		(fp_poly
			(pts
				(xy 3.5179 -3.5179) (xy 2.2479 -3.5179) (xy 3.5179 -2.2479)
			)
			(stroke
				(width 0)
				(type default)
			)
			(fill yes)
			(layer "F.SilkS")
		)
		(fp_rect
			(start -2.5019 2.5019)
			(end 2.5019 -2.5019)
			(stroke
				(width 0)
				(type default)
			)
			(fill no)
			(layer "F.CrtYd")
		)
		(fp_poly
			(pts
				(xy -3.5179 3.5179) (xy -3.5179 -3.5179) (xy 3.5179 -3.5179) (xy 3.5179 -2.5019) (xy -2.5019 -2.5019)
				(xy -2.5019 2.5019) (xy 2.5019 2.5019) (xy 2.5019 -2.49682) (xy 3.5179 -2.49682) (xy 3.5179 3.5179)
			)
			(stroke
				(width 0)
				(type default)
			)
			(fill no)
			(layer "F.CrtYd")
		)
		(fp_rect
			(start -3.5179 3.5179)
			(end 3.5179 -3.5179)
			(stroke
				(width 0)
				(type default)
			)
			(fill no)
			(layer "F.Fab")
		)
		(pad "1" smd rect
			(at 1.299972 -2.474722 270)
			(size 0.3556 1.0668)
			(layers "F.Cu" "F.Mask" "F.Paste")
			(net "TPS74801_P2V5_STBY_OUT")
		)
		(pad "2" smd rect
			(at 0.649986 -2.474722 270)
			(size 0.3556 1.0668)
			(layers "F.Cu" "F.Mask" "F.Paste")
			(net "GND")
		)
		(pad "3" smd rect
			(at 0 -2.474722 270)
			(size 0.3556 1.0668)
			(layers "F.Cu" "F.Mask" "F.Paste")
			(net "GND")
		)
		(pad "4" smd rect
			(at -0.649986 -2.474722 270)
			(size 0.3556 1.0668)
			(layers "F.Cu" "F.Mask" "F.Paste")
			(net "GND")
		)
		(pad "5" smd rect
			(at -1.299972 -2.474722 270)
			(size 0.3556 1.0668)
			(layers "F.Cu" "F.Mask" "F.Paste")
			(net "P3V3_STBY")
		)
		(pad "6" smd rect
			(at -2.474722 -1.299972 270)
			(size 1.0668 0.3556)
			(layers "F.Cu" "F.Mask" "F.Paste")
			(net "P3V3_STBY")
		)
		(pad "7" smd rect
			(at -2.474722 -0.649986 270)
			(size 1.0668 0.3556)
			(layers "F.Cu" "F.Mask" "F.Paste")
			(net "P3V3_STBY")
		)
		(pad "8" smd rect
			(at -2.474722 0 270)
			(size 1.0668 0.3556)
			(layers "F.Cu" "F.Mask" "F.Paste")
			(net "P3V3_STBY")
		)
		(pad "9" smd rect
			(at -2.474722 0.649986 270)
			(size 1.0668 0.3556)
			(layers "F.Cu" "F.Mask" "F.Paste")
			(net "PWRGD_P2V5_STBY")
		)
		(pad "10" smd rect
			(at -2.474722 1.299972 270)
			(size 1.0668 0.3556)
			(layers "F.Cu" "F.Mask" "F.Paste")
			(net "TPS74801_P2V5_STBY_BIAS")
		)
		(pad "11" smd rect
			(at -1.299972 2.474722 270)
			(size 0.3556 1.0668)
			(layers "F.Cu" "F.Mask" "F.Paste")
			(net "TPS74801_P2V5_STBY_EN")
		)
		(pad "12" smd rect
			(at -0.649986 2.474722 270)
			(size 0.3556 1.0668)
			(layers "F.Cu" "F.Mask" "F.Paste")
			(net "GND")
		)
		(pad "13" smd rect
			(at 0 2.474722 270)
			(size 0.3556 1.0668)
			(layers "F.Cu" "F.Mask" "F.Paste")
			(net "GND")
		)
		(pad "14" smd rect
			(at 0.649986 2.474722 270)
			(size 0.3556 1.0668)
			(layers "F.Cu" "F.Mask" "F.Paste")
			(net "GND")
		)
		(pad "15" smd rect
			(at 1.299972 2.474722 270)
			(size 0.3556 1.0668)
			(layers "F.Cu" "F.Mask" "F.Paste")
			(net "TPS74801_P2V5_STBY_SS")
		)
		(pad "16" smd rect
			(at 2.474722 1.299972 270)
			(size 1.0668 0.3556)
			(layers "F.Cu" "F.Mask" "F.Paste")
			(net "TPS74801_P2V5_STBY_FB")
		)
		(pad "17" smd rect
			(at 2.474722 0.649986 270)
			(size 1.0668 0.3556)
			(layers "F.Cu" "F.Mask" "F.Paste")
			(net "GND")
		)
		(pad "18" smd rect
			(at 2.474722 0 270)
			(size 1.0668 0.3556)
			(layers "F.Cu" "F.Mask" "F.Paste")
			(net "TPS74801_P2V5_STBY_OUT")
		)
		(pad "19" smd rect
			(at 2.474722 -0.649986 270)
			(size 1.0668 0.3556)
			(layers "F.Cu" "F.Mask" "F.Paste")
			(net "TPS74801_P2V5_STBY_OUT")
		)
		(pad "20" smd rect
			(at 2.474722 -1.299972 270)
			(size 1.0668 0.3556)
			(layers "F.Cu" "F.Mask" "F.Paste")
			(net "TPS74801_P2V5_STBY_OUT")
		)
		(pad "21" smd rect
			(at 0 0 270)
			(size 3.2512 3.2512)
			(layers "F.Cu" "F.Mask" "F.Paste")
			(net "GND")
		)
	)
)
